(kicad_pcb
	(version 20260206)
	(generator "pcbnew")
	(generator_version "10.0")
	(general
		(thickness 1.6)
		(legacy_teardrops no)
	)
	(paper "A4")
	(title_block
		(title "Bryce Canyon_IOM_IOC_16318-2_OCP.brd")
		(comment 1 "Bryce Canyon / footprints 539-545 of 1605")
	)
	(layers
		(0 "F.Cu" signal "TOP")
		(4 "In1.Cu" signal "L2GND")
		(6 "In2.Cu" signal "L3")
		(8 "In3.Cu" signal "L4VCC")
		(10 "In4.Cu" signal "L5VCC")
		(12 "In5.Cu" signal "L6")
		(14 "In6.Cu" signal "L7GND")
		(2 "B.Cu" signal "BOTTOM")
		(9 "F.Adhes" user "F.Adhesive")
		(11 "B.Adhes" user "B.Adhesive")
		(13 "F.Paste" user "Package Geometry/Pastemask Top")
		(15 "B.Paste" user "Package Geometry/Pastemask Bottom")
		(5 "F.SilkS" user "Ref Des/Silkscreen Top")
		(7 "B.SilkS" user "Ref Des/Silkscreen Bottom")
		(1 "F.Mask" user "Board Geometry/Soldermask Top")
		(3 "B.Mask" user "Board Geometry/Soldermask Bottom")
		(17 "Dwgs.User" user "User.Drawings")
		(19 "Cmts.User" user "User.Comments")
		(21 "Eco1.User" user "User.Eco1")
		(23 "Eco2.User" user "User.Eco2")
		(25 "Edge.Cuts" user "Board Geometry/Outline")
		(27 "Margin" user)
		(31 "F.CrtYd" user "Package Geometry/Place Bound Top")
		(29 "B.CrtYd" user "Package Geometry/Place Bound Bottom")
		(35 "F.Fab" user "Ref Des/Assembly Top")
		(33 "B.Fab" user "Ref Des/Assembly Bottom")
	)
	(footprint ""
		(layer "F.Cu")
		(at 124.841 -8.636 90)
		(property "Reference" "R435"
			(at 0 0 90)
			(layer "F.SilkS")
			(hide yes)
			(effects
				(font
					(size 1.27 1.27)
				)
			)
		)
		(property "Value" "3K83R2F-GP"
			(at 0.064008 -3.993896 90)
			(unlocked yes)
			(layer "F.Fab")
			(hide yes)
			(effects
				(font
					(size 1.016 1.016)
					(thickness 0.1524)
				)
			)
		)
		(property "Device Type" "R402H16"
			(at 0.064008 -5.517896 90)
			(unlocked yes)
			(layer "F.Fab")
			(hide yes)
			(effects
				(font
					(size 1.016 1.016)
					(thickness 0.1524)
				)
			)
		)
		(duplicate_pad_numbers_are_jumpers no)
		(fp_line
			(start 0.508 -0.9398)
			(end -0.508 -0.9398)
			(stroke
				(width 0.1524)
				(type default)
			)
			(layer "F.SilkS")
		)
		(fp_line
			(start -0.508 -0.9398)
			(end -0.508 0.9398)
			(stroke
				(width 0.1524)
				(type default)
			)
			(layer "F.SilkS")
		)
		(fp_rect
			(start -0.508 0.9398)
			(end 0.508 -0.9398)
			(stroke
				(width 0)
				(type default)
			)
			(fill no)
			(layer "F.CrtYd")
		)
		(fp_rect
			(start -0.508 0.9398)
			(end 0.508 -0.9398)
			(stroke
				(width 0)
				(type default)
			)
			(fill no)
			(layer "F.Fab")
		)
		(pad "1" smd custom
			(at 0 -0.4445 90)
			(size 0.1397 0.1397)
			(layers "F.Cu" "F.Mask" "F.Paste")
			(net "P12V_IOM_PGOOD")
			(options
				(clearance outline)
				(anchor circle)
			)
			(primitives
				(gr_poly
					(pts
						(arc
							(start -0.1778 -0.2794)
							(mid -0.249642 -0.249642)
							(end -0.2794 -0.1778)
						)
						(arc
							(start -0.2794 0.1778)
							(mid -0.249642 0.249642)
							(end -0.1778 0.2794)
						)
						(arc
							(start 0.1778 0.2794)
							(mid 0.249642 0.249642)
							(end 0.2794 0.1778)
						)
						(arc
							(start 0.2794 -0.1778)
							(mid 0.249642 -0.249642)
							(end 0.1778 -0.2794)
						)
					)
					(width 0)
					(fill yes)
				)
			)
		)
		(pad "2" smd custom
			(at 0 0.4445 90)
			(size 0.1397 0.1397)
			(layers "F.Cu" "F.Mask" "F.Paste")
			(net "GND")
			(options
				(clearance outline)
				(anchor circle)
			)
			(primitives
				(gr_poly
					(pts
						(arc
							(start -0.1778 -0.2794)
							(mid -0.249642 -0.249642)
							(end -0.2794 -0.1778)
						)
						(arc
							(start -0.2794 0.1778)
							(mid -0.249642 0.249642)
							(end -0.1778 0.2794)
						)
						(arc
							(start 0.1778 0.2794)
							(mid 0.249642 0.249642)
							(end 0.2794 0.1778)
						)
						(arc
							(start 0.2794 -0.1778)
							(mid 0.249642 -0.249642)
							(end 0.1778 -0.2794)
						)
					)
					(width 0)
					(fill yes)
				)
			)
		)
	)
	(footprint ""
		(layer "F.Cu")
		(at 88.245188 -62.817756 -90)
		(property "Reference" "R7"
			(at 0 0 270)
			(layer "F.SilkS")
			(hide yes)
			(effects
				(font
					(size 1.27 1.27)
				)
			)
		)
		(property "Value" "0R2J-2-GP"
			(at 0.064008 -3.993896 270)
			(unlocked yes)
			(layer "F.Fab")
			(hide yes)
			(effects
				(font
					(size 1.016 1.016)
					(thickness 0.1524)
				)
			)
		)
		(property "Device Type" "R402H16"
			(at 0.064008 -5.517896 270)
			(unlocked yes)
			(layer "F.Fab")
			(hide yes)
			(effects
				(font
					(size 1.016 1.016)
					(thickness 0.1524)
				)
			)
		)
		(duplicate_pad_numbers_are_jumpers no)
		(fp_line
			(start -0.508 -0.9398)
			(end -0.508 0.9398)
			(stroke
				(width 0.1524)
				(type default)
			)
			(layer "F.SilkS")
		)
		(fp_line
			(start 0.508 -0.9398)
			(end -0.508 -0.9398)
			(stroke
				(width 0.1524)
				(type default)
			)
			(layer "F.SilkS")
		)
		(fp_rect
			(start -0.508 0.9398)
			(end 0.508 -0.9398)
			(stroke
				(width 0)
				(type default)
			)
			(fill no)
			(layer "F.CrtYd")
		)
		(fp_rect
			(start -0.508 0.9398)
			(end 0.508 -0.9398)
			(stroke
				(width 0)
				(type default)
			)
			(fill no)
			(layer "F.Fab")
		)
		(pad "1" smd custom
			(at 0 -0.4445 270)
			(size 0.1397 0.1397)
			(layers "F.Cu" "F.Mask" "F.Paste")
			(net "NCSI_TXEN")
			(options
				(clearance outline)
				(anchor circle)
			)
			(primitives
				(gr_poly
					(pts
						(arc
							(start -0.1778 -0.2794)
							(mid -0.249642 -0.249642)
							(end -0.2794 -0.1778)
						)
						(arc
							(start -0.2794 0.1778)
							(mid -0.249642 0.249642)
							(end -0.1778 0.2794)
						)
						(arc
							(start 0.1778 0.2794)
							(mid 0.249642 0.249642)
							(end 0.2794 0.1778)
						)
						(arc
							(start 0.2794 -0.1778)
							(mid 0.249642 -0.249642)
							(end 0.1778 -0.2794)
						)
					)
					(width 0)
					(fill yes)
				)
			)
		)
		(pad "2" smd custom
			(at 0 0.4445 270)
			(size 0.1397 0.1397)
			(layers "F.Cu" "F.Mask" "F.Paste")
			(net "NCSI_TXEN_R")
			(options
				(clearance outline)
				(anchor circle)
			)
			(primitives
				(gr_poly
					(pts
						(arc
							(start -0.1778 -0.2794)
							(mid -0.249642 -0.249642)
							(end -0.2794 -0.1778)
						)
						(arc
							(start -0.2794 0.1778)
							(mid -0.249642 0.249642)
							(end -0.1778 0.2794)
						)
						(arc
							(start 0.1778 0.2794)
							(mid 0.249642 0.249642)
							(end 0.2794 0.1778)
						)
						(arc
							(start 0.2794 -0.1778)
							(mid 0.249642 -0.249642)
							(end 0.1778 -0.2794)
						)
					)
					(width 0)
					(fill yes)
				)
			)
		)
	)
	(footprint ""
		(layer "F.Cu")
		(at 183.515 -88.392)
		(property "Reference" "R627"
			(at 0 0 0)
			(layer "F.SilkS")
			(hide yes)
			(effects
				(font
					(size 1.27 1.27)
				)
			)
		)
		(property "Value" "4K7R2F-GP"
			(at 0.064008 -3.993896 0)
			(unlocked yes)
			(layer "F.Fab")
			(hide yes)
			(effects
				(font
					(size 1.016 1.016)
					(thickness 0.1524)
				)
			)
		)
		(property "Device Type" "R402H16"
			(at 0.064008 -5.517896 0)
			(unlocked yes)
			(layer "F.Fab")
			(hide yes)
			(effects
				(font
					(size 1.016 1.016)
					(thickness 0.1524)
				)
			)
		)
		(duplicate_pad_numbers_are_jumpers no)
		(fp_line
			(start -0.508 -0.9398)
			(end -0.508 0.9398)
			(stroke
				(width 0.1524)
				(type default)
			)
			(layer "F.SilkS")
		)
		(fp_line
			(start 0.508 -0.9398)
			(end -0.508 -0.9398)
			(stroke
				(width 0.1524)
				(type default)
			)
			(layer "F.SilkS")
		)
		(fp_rect
			(start -0.508 0.9398)
			(end 0.508 -0.9398)
			(stroke
				(width 0)
				(type default)
			)
			(fill no)
			(layer "F.CrtYd")
		)
		(fp_rect
			(start -0.508 0.9398)
			(end 0.508 -0.9398)
			(stroke
				(width 0)
				(type default)
			)
			(fill no)
			(layer "F.Fab")
		)
		(pad "1" smd custom
			(at 0 -0.4445)
			(size 0.1397 0.1397)
			(layers "F.Cu" "F.Mask" "F.Paste")
			(net "P1V8")
			(options
				(clearance outline)
				(anchor circle)
			)
			(primitives
				(gr_poly
					(pts
						(arc
							(start -0.1778 -0.2794)
							(mid -0.249642 -0.249642)
							(end -0.2794 -0.1778)
						)
						(arc
							(start -0.2794 0.1778)
							(mid -0.249642 0.249642)
							(end -0.1778 0.2794)
						)
						(arc
							(start 0.1778 0.2794)
							(mid 0.249642 0.249642)
							(end 0.2794 0.1778)
						)
						(arc
							(start 0.2794 -0.1778)
							(mid 0.249642 -0.249642)
							(end 0.1778 -0.2794)
						)
					)
					(width 0)
					(fill yes)
				)
			)
		)
		(pad "2" smd custom
			(at 0 0.4445)
			(size 0.1397 0.1397)
			(layers "F.Cu" "F.Mask" "F.Paste")
			(net "SYS_HALT0#")
			(options
				(clearance outline)
				(anchor circle)
			)
			(primitives
				(gr_poly
					(pts
						(arc
							(start -0.1778 -0.2794)
							(mid -0.249642 -0.249642)
							(end -0.2794 -0.1778)
						)
						(arc
							(start -0.2794 0.1778)
							(mid -0.249642 0.249642)
							(end -0.1778 0.2794)
						)
						(arc
							(start 0.1778 0.2794)
							(mid 0.249642 0.249642)
							(end 0.2794 0.1778)
						)
						(arc
							(start 0.2794 -0.1778)
							(mid 0.249642 -0.249642)
							(end 0.1778 -0.2794)
						)
					)
					(width 0)
					(fill yes)
				)
			)
		)
	)
	(footprint ""
		(layer "F.Cu")
		(at 153.383742 -97.335594 180)
		(property "Reference" "Q16"
			(at 0 0 180)
			(layer "F.SilkS")
			(hide yes)
			(effects
				(font
					(size 1.27 1.27)
				)
			)
		)
		(property "Value" "2N7002K-1-GP"
			(at 0.127 -8.9662 180)
			(unlocked yes)
			(layer "F.Fab")
			(hide yes)
			(effects
				(font
					(size 1.016 1.016)
					(thickness 0.1524)
				)
			)
		)
		(property "Device Type" "SOT23DGS2D4H44"
			(at 0.127 -10.4902 180)
			(unlocked yes)
			(layer "F.Fab")
			(hide yes)
			(effects
				(font
					(size 1.016 1.016)
					(thickness 0.1524)
				)
			)
		)
		(duplicate_pad_numbers_are_jumpers no)
		(fp_line
			(start 1.651 1.778)
			(end 1.651 -1.778)
			(stroke
				(width 0.1524)
				(type default)
			)
			(layer "F.SilkS")
		)
		(fp_line
			(start 1.651 -1.778)
			(end -1.651 -1.778)
			(stroke
				(width 0.1524)
				(type default)
			)
			(layer "F.SilkS")
		)
		(fp_line
			(start -1.651 1.778)
			(end 1.651 1.778)
			(stroke
				(width 0.1524)
				(type default)
			)
			(layer "F.SilkS")
		)
		(fp_line
			(start -1.651 -1.778)
			(end -1.651 1.778)
			(stroke
				(width 0.1524)
				(type default)
			)
			(layer "F.SilkS")
		)
		(fp_poly
			(pts
				(xy -1.778 1.8796) (xy -1.778 -1.8796) (xy 1.778 -1.8796) (xy 1.778 1.8796)
			)
			(stroke
				(width 0)
				(type default)
			)
			(fill no)
			(layer "F.CrtYd")
		)
		(fp_poly
			(pts
				(xy -1.778 1.8796) (xy -1.778 -1.8796) (xy 1.778 -1.8796) (xy 1.778 1.8796)
			)
			(stroke
				(width 0)
				(type default)
			)
			(fill no)
			(layer "F.Fab")
		)
		(pad "D" smd custom
			(at 0 -0.9525 180)
			(size 0.1905 0.1905)
			(layers "F.Cu" "F.Mask" "F.Paste")
			(net "SYS_RST_N_0")
			(options
				(clearance outline)
				(anchor circle)
			)
			(primitives
				(gr_poly
					(pts
						(arc
							(start -0.1778 0.5715)
							(mid -0.321484 0.511984)
							(end -0.381 0.3683)
						)
						(arc
							(start -0.381 -0.3683)
							(mid -0.321484 -0.511984)
							(end -0.1778 -0.5715)
						)
						(arc
							(start 0.1778 -0.5715)
							(mid 0.321484 -0.511984)
							(end 0.381 -0.3683)
						)
						(arc
							(start 0.381 0.3683)
							(mid 0.321484 0.511984)
							(end 0.1778 0.5715)
						)
					)
					(width 0)
					(fill yes)
				)
			)
		)
		(pad "G" smd custom
			(at -0.98425 0.9525 180)
			(size 0.1905 0.1905)
			(layers "F.Cu" "F.Mask" "F.Paste")
			(net "P3V3_STBY_G")
			(options
				(clearance outline)
				(anchor circle)
			)
			(primitives
				(gr_poly
					(pts
						(arc
							(start -0.1778 0.5715)
							(mid -0.321484 0.511984)
							(end -0.381 0.3683)
						)
						(arc
							(start -0.381 -0.3683)
							(mid -0.321484 -0.511984)
							(end -0.1778 -0.5715)
						)
						(arc
							(start 0.1778 -0.5715)
							(mid 0.321484 -0.511984)
							(end 0.381 -0.3683)
						)
						(arc
							(start 0.381 0.3683)
							(mid 0.321484 0.511984)
							(end 0.1778 0.5715)
						)
					)
					(width 0)
					(fill yes)
				)
			)
		)
		(pad "S" smd custom
			(at 0.98425 0.9525 180)
			(size 0.1905 0.1905)
			(layers "F.Cu" "F.Mask" "F.Paste")
			(net "GND")
			(options
				(clearance outline)
				(anchor circle)
			)
			(primitives
				(gr_poly
					(pts
						(arc
							(start -0.1778 0.5715)
							(mid -0.321484 0.511984)
							(end -0.381 0.3683)
						)
						(arc
							(start -0.381 -0.3683)
							(mid -0.321484 -0.511984)
							(end -0.1778 -0.5715)
						)
						(arc
							(start 0.1778 -0.5715)
							(mid 0.321484 -0.511984)
							(end 0.381 -0.3683)
						)
						(arc
							(start 0.381 0.3683)
							(mid 0.321484 0.511984)
							(end 0.1778 0.5715)
						)
					)
					(width 0)
					(fill yes)
				)
			)
		)
	)
	(footprint ""
		(layer "F.Cu")
		(at 29.755846 -186.56681 180)
		(property "Reference" "C177"
			(at 0 0 180)
			(layer "F.SilkS")
			(hide yes)
			(effects
				(font
					(size 1.27 1.27)
				)
			)
		)
		(property "Value" "SC10U16V5KX-7-GP-U"
			(at -0.0762 -6.1214 180)
			(unlocked yes)
			(layer "F.Fab")
			(hide yes)
			(effects
				(font
					(size 1.016 1.016)
					(thickness 0.1524)
				)
			)
		)
		(property "Device Type" "C805H58"
			(at -0.0762 -8.1534 180)
			(unlocked yes)
			(layer "F.Fab")
			(hide yes)
			(effects
				(font
					(size 1.016 1.016)
					(thickness 0.1524)
				)
			)
		)
		(duplicate_pad_numbers_are_jumpers no)
		(fp_line
			(start 0.635 0)
			(end -0.635 0)
			(stroke
				(width 0.508)
				(type default)
			)
			(layer "F.SilkS")
		)
		(fp_rect
			(start -0.9652 1.778)
			(end 0.9652 -1.778)
			(stroke
				(width 0)
				(type default)
			)
			(fill no)
			(layer "F.CrtYd")
		)
		(fp_poly
			(pts
				(xy -0.9652 -1.778) (xy 0.9652 -1.778) (xy 0.9652 1.778) (xy -0.9652 1.778)
			)
			(stroke
				(width 0)
				(type default)
			)
			(fill no)
			(layer "F.Fab")
		)
		(pad "1" smd rect
			(at 0 -0.9652 180)
			(size 1.397 1.143)
			(layers "F.Cu" "F.Mask" "F.Paste")
			(net "P12V_STBY_VIN_PU2")
		)
		(pad "2" smd rect
			(at 0 0.9652 180)
			(size 1.397 1.143)
			(layers "F.Cu" "F.Mask" "F.Paste")
			(net "GND")
		)
	)
	(footprint ""
		(layer "F.Cu")
		(at 154.559 -85.7758 180)
		(property "Reference" "R694"
			(at 0 0 180)
			(layer "F.SilkS")
			(hide yes)
			(effects
				(font
					(size 1.27 1.27)
				)
			)
		)
		(property "Value" "0R2J-2-GP"
			(at 0.064008 -3.993896 180)
			(unlocked yes)
			(layer "F.Fab")
			(hide yes)
			(effects
				(font
					(size 1.016 1.016)
					(thickness 0.1524)
				)
			)
		)
		(property "Device Type" "R402H16"
			(at 0.064008 -5.517896 180)
			(unlocked yes)
			(layer "F.Fab")
			(hide yes)
			(effects
				(font
					(size 1.016 1.016)
					(thickness 0.1524)
				)
			)
		)
		(duplicate_pad_numbers_are_jumpers no)
		(fp_line
			(start 0.508 -0.9398)
			(end -0.508 -0.9398)
			(stroke
				(width 0.1524)
				(type default)
			)
			(layer "F.SilkS")
		)
		(fp_line
			(start -0.508 -0.9398)
			(end -0.508 0.9398)
			(stroke
				(width 0.1524)
				(type default)
			)
			(layer "F.SilkS")
		)
		(fp_rect
			(start -0.508 0.9398)
			(end 0.508 -0.9398)
			(stroke
				(width 0)
				(type default)
			)
			(fill no)
			(layer "F.CrtYd")
		)
		(fp_rect
			(start -0.508 0.9398)
			(end 0.508 -0.9398)
			(stroke
				(width 0)
				(type default)
			)
			(fill no)
			(layer "F.Fab")
		)
		(pad "1" smd custom
			(at 0 -0.4445 180)
			(size 0.1397 0.1397)
			(layers "F.Cu" "F.Mask" "F.Paste")
			(net "IOM_IOC_UART_RX")
			(options
				(clearance outline)
				(anchor circle)
			)
			(primitives
				(gr_poly
					(pts
						(arc
							(start -0.1778 -0.2794)
							(mid -0.249642 -0.249642)
							(end -0.2794 -0.1778)
						)
						(arc
							(start -0.2794 0.1778)
							(mid -0.249642 0.249642)
							(end -0.1778 0.2794)
						)
						(arc
							(start 0.1778 0.2794)
							(mid 0.249642 0.249642)
							(end 0.2794 0.1778)
						)
						(arc
							(start 0.2794 -0.1778)
							(mid 0.249642 -0.249642)
							(end 0.1778 -0.2794)
						)
					)
					(width 0)
					(fill yes)
				)
			)
		)
		(pad "2" smd custom
			(at 0 0.4445 180)
			(size 0.1397 0.1397)
			(layers "F.Cu" "F.Mask" "F.Paste")
			(net "IOC_UART_R_RX")
			(options
				(clearance outline)
				(anchor circle)
			)
			(primitives
				(gr_poly
					(pts
						(arc
							(start -0.1778 -0.2794)
							(mid -0.249642 -0.249642)
							(end -0.2794 -0.1778)
						)
						(arc
							(start -0.2794 0.1778)
							(mid -0.249642 0.249642)
							(end -0.1778 0.2794)
						)
						(arc
							(start 0.1778 0.2794)
							(mid 0.249642 0.249642)
							(end 0.2794 0.1778)
						)
						(arc
							(start 0.2794 -0.1778)
							(mid 0.249642 -0.249642)
							(end 0.1778 -0.2794)
						)
					)
					(width 0)
					(fill yes)
				)
			)
		)
	)
	(footprint ""
		(layer "F.Cu")
		(at 76.4286 -143.3068 90)
		(property "Reference" "R130"
			(at 0 0 90)
			(layer "F.SilkS")
			(hide yes)
			(effects
				(font
					(size 1.27 1.27)
				)
			)
		)
		(property "Value" "0R2J-2-GP"
			(at 0.064008 -3.993896 90)
			(unlocked yes)
			(layer "F.Fab")
			(hide yes)
			(effects
				(font
					(size 1.016 1.016)
					(thickness 0.1524)
				)
			)
		)
		(property "Device Type" "R402H16"
			(at 0.064008 -5.517896 90)
			(unlocked yes)
			(layer "F.Fab")
			(hide yes)
			(effects
				(font
					(size 1.016 1.016)
					(thickness 0.1524)
				)
			)
		)
		(duplicate_pad_numbers_are_jumpers no)
		(fp_line
			(start 0.508 -0.9398)
			(end -0.508 -0.9398)
			(stroke
				(width 0.1524)
				(type default)
			)
			(layer "F.SilkS")
		)
		(fp_line
			(start -0.508 -0.9398)
			(end -0.508 0.9398)
			(stroke
				(width 0.1524)
				(type default)
			)
			(layer "F.SilkS")
		)
		(fp_rect
			(start -0.508 0.9398)
			(end 0.508 -0.9398)
			(stroke
				(width 0)
				(type default)
			)
			(fill no)
			(layer "F.CrtYd")
		)
		(fp_rect
			(start -0.508 0.9398)
			(end 0.508 -0.9398)
			(stroke
				(width 0)
				(type default)
			)
			(fill no)
			(layer "F.Fab")
		)
		(pad "1" smd custom
			(at 0 -0.4445 90)
			(size 0.1397 0.1397)
			(layers "F.Cu" "F.Mask" "F.Paste")
			(net "I2C_EXP_RMT_SDA")
			(options
				(clearance outline)
				(anchor circle)
			)
			(primitives
				(gr_poly
					(pts
						(arc
							(start -0.1778 -0.2794)
							(mid -0.249642 -0.249642)
							(end -0.2794 -0.1778)
						)
						(arc
							(start -0.2794 0.1778)
							(mid -0.249642 0.249642)
							(end -0.1778 0.2794)
						)
						(arc
							(start 0.1778 0.2794)
							(mid 0.249642 0.249642)
							(end 0.2794 0.1778)
						)
						(arc
							(start 0.2794 -0.1778)
							(mid 0.249642 -0.249642)
							(end 0.1778 -0.2794)
						)
					)
					(width 0)
					(fill yes)
				)
			)
		)
		(pad "2" smd custom
			(at 0 0.4445 90)
			(size 0.1397 0.1397)
			(layers "F.Cu" "F.Mask" "F.Paste")
			(net "I2C_EXP_RMT_SDA_R")
			(options
				(clearance outline)
				(anchor circle)
			)
			(primitives
				(gr_poly
					(pts
						(arc
							(start -0.1778 -0.2794)
							(mid -0.249642 -0.249642)
							(end -0.2794 -0.1778)
						)
						(arc
							(start -0.2794 0.1778)
							(mid -0.249642 0.249642)
							(end -0.1778 0.2794)
						)
						(arc
							(start 0.1778 0.2794)
							(mid 0.249642 0.249642)
							(end 0.2794 0.1778)
						)
						(arc
							(start 0.2794 -0.1778)
							(mid 0.249642 -0.249642)
							(end 0.1778 -0.2794)
						)
					)
					(width 0)
					(fill yes)
				)
			)
		)
	)
)
